FILE_TYPE = MULTI_PHYS_TABLE;
PART 'TTL2G14'
{====================================================================================================================================================================================================================================}
:VALUE      | PACK_TYPE | MATERIAL | PART_NUMBER     = EnvComp | PART_NUMBER  | JEDEC_TYPE      | DESCRIPTION                        | CLASS | HEIGHT     | COMPONENT_TYPE | LEAD_LENGTH | LPID   | SPEED_URL | Status |RPL| AML | Bus_Unit | Days ;
{====================================================================================================================================================================================================================================}
'74LVC2G14' | 'SMLF'    | 'IC'     | 'D18476-001'(!) = 'YES;YES;YES;UNK;ok;VLD' | 'D18476-001' | 'SSOP6_67_95MA' | 'DUAL INVERTER GATE'               | 'IC'  | '0.057 IN' | 'SMALLSMT'     | ''          | '354' | 'http://speed.intel.com:8081/speed/module/pdm/item/pdm_item_detail_direct.asp?item_cde=D18476-001&item_rev=01&url_param=unused' | 'Approved' | 'YES' | '1' | 'SMO_IC' | '84' 
'74LVC2G14' | 'SMLF'    | 'EMPTY'  | 'D18476-001'(!) = 'YES;YES;YES;UNK;ok;VLD' | 'D18476-001' | 'SSOP6_67_95MA' | 'DUAL INVERTER GATE'               | 'IO'  | '0.057 IN' | 'SMALLSMT'     | ''          | '354' | 'http://speed.intel.com:8081/speed/module/pdm/item/pdm_item_detail_direct.asp?item_cde=D18476-001&item_rev=01&url_param=unused' | 'Approved' | 'YES' | '1' | 'SMO_IC' | '84' 
END_PART
END.
